Testpoint Report Status for Project:16316-1

Total # of Nets  : 1093

Number of nets with "No_Test" property      :   477
Number of nets with testpoints assigned >1  :   17
Number of nets with testpoints assigned =1  :   584
Number of nets with testpoints assigned =0  :   15

Percent (All nets)                              :  54.99%
Percent (All nets Excluded "No_Test" property)  :  97.56%

AGND_P1V5_E                            4
AGND_P3V3                              4
GB_VDDA                                8
GB_VDDH                                4
GND                                   13
P0V9                                   8
P12V_MAIN                              8
P12V_STBY_VIN_Q7                       4
P12V_STBY_VIN_U10                      3
P1V5_E                                 3
P1V5_E_OUT                             3
P1V8_C                                 8
P1V8_E                                 8
P3V3                                   9
P3V3_LL                                7
P5V                                    4
SAS0_AVDD                              6

AGND_CURRENT_MON                       1
AGND_P0V9                              1
AGND_P0V975                            1
AVSO_IDDTN18                           1
AVSO_VREF                              1
BMC_EXP_SPARE_0_R_LS                   1
BMC_EXP_SPARE_1_R_LS                   1
BMC_LOC_HEARTBEAT                      1
BMC_LOC_HEARTBEAT_LS                   1
BMC_RMT_HEARTBEAT                      1
BMC_RMT_HEARTBEAT_LS                   1
BMC_SPARE_0                            1
BMC_SPARE_0_LS                         1
BMC_SPARE_1                            1
BMC_SPARE_1_LS                         1
COMP_EXP_SPARE_1_R_LS                  1
COMP_SPARE_0                           1
COMP_SPARE_0_LS                        1
CP_DONE                                1
DDR_BZ                                 1
DEBUG_HIGH_HEX_0                       1
DEBUG_HIGH_HEX_1                       1
DEBUG_HIGH_HEX_2                       1
DEBUG_HIGH_HEX_3                       1
DEBUG_LOW_HEX_0                        1
DEBUG_LOW_HEX_1                        1
DEBUG_LOW_HEX_2                        1
DEBUG_LOW_HEX_3                        1
DRIVE_0_ACT                            1
DRIVE_12_ACT                           1
DRIVE_13_ACT                           1
DRIVE_14_ACT                           1
DRIVE_15_ACT                           1
DRIVE_16_ACT                           1
DRIVE_17_ACT                           1
DRIVE_18_ACT                           1
DRIVE_19_ACT                           1
DRIVE_1_ACT                            1
DRIVE_20_ACT                           1
DRIVE_21_ACT                           1
DRIVE_22_ACT                           1
DRIVE_23_ACT                           1
DRIVE_24_ACT                           1
DRIVE_25_ACT                           1
DRIVE_26_ACT                           1
DRIVE_27_ACT                           1
DRIVE_28_ACT                           1
DRIVE_29_ACT                           1
DRIVE_2_ACT                            1
DRIVE_30_ACT                           1
DRIVE_31_ACT                           1
DRIVE_32_ACT                           1
DRIVE_33_ACT                           1
DRIVE_34_ACT                           1
DRIVE_35_ACT                           1
DRIVE_36_ACT                           1
DRIVE_37_ACT                           1
DRIVE_38_ACT                           1
DRIVE_39_ACT                           1
DRIVE_3_ACT                            1
DRIVE_4_ACT                            1
DRIVE_5_ACT                            1
DRIVE_6_ACT                            1
DRIVE_7_ACT                            1
DRIVE_INSERT_ALERT_LS_N                1
DRIVE_INSERT_ALERT_N                   1
EEPROM_SCL                             1
EEPROM_SDA                             1
EEPROM_WP                              1
ENCL_FAULT_LED                         1
ENCL_FAULT_LED_LS                      1
EXP_ADC_IN0                            1
EXP_ADC_IN1                            1
EXP_BLINK_IN                           1
EXP_BLINK_OUT                          1
EXP_CLK_SEL0                           1
EXP_CLK_SEL1                           1
EXP_CPU_MODE_0                         1
EXP_CPU_MODE_1                         1
EXP_EEPROM_A0                          1
EXP_EEPROM_A1                          1
EXP_EEPROM_A2                          1
EXP_EEPROM_SCL                         1
EXP_EEPROM_SDA                         1
EXP_EEPROM_WP                          1
EXP_GPIO1                              1
EXP_GPIO12                             1
EXP_GPIO13                             1
EXP_GPIO14                             1
EXP_GPIO15                             1
EXP_HW_LED_D                           1
EXP_HW_LED_R                           1
EXP_I2C_SCL10                          1
EXP_I2C_SCL11                          1
EXP_I2C_SCL9                           1
EXP_I2C_SDA10                          1
EXP_I2C_SDA11                          1
EXP_I2C_SDA9                           1
EXP_IDDT                               1
EXP_RESET_N                            1
EXP_RESET_R_U23_N                      1
EXP_RGMII_RXC                          1
EXP_SIO_CLK_IN                         1
EXP_SIO_CLK_OUT                        1
EXP_SIO_D_IN                           1
EXP_SIO_D_OUT                          1
EXP_SIO_LOAD_IN                        1
EXP_SIO_LOAD_OUT                       1
EXP_SMART_RX_R                         1
EXP_SMART_TX_R                         1
EXP_SYS_RST_N                          1
EXP_WP_N                               1
FRU_EEPROM_A0                          1
FRU_EEPROM_A1                          1
FRU_EEPROM_A2                          1
FW_RESET_N                             1
GND_SENSE                              1
HM40ADC_VDDA                           1
HSW_SCL_2                              1
HSW_SDA_2                              1
I2C_BMC_LOC_SCL0                       1
I2C_BMC_LOC_SCL0_LS                    1
I2C_BMC_LOC_SDA0                       1
I2C_BMC_LOC_SDA0_LS                    1
I2C_BMC_RMT_SCL1                       1
I2C_BMC_RMT_SCL1_LS                    1
I2C_BMC_RMT_SDA1                       1
I2C_BMC_RMT_SDA1_LS                    1
I2C_CLIP_SCL7                          1
I2C_CLIP_SCL7_LS                       1
I2C_CLIP_SDA7                          1
I2C_CLIP_SDA7_LS                       1
I2C_DPB_SCL3                           1
I2C_DPB_SCL3_LS                        1
I2C_DPB_SDA3                           1
I2C_DPB_SDA3_LS                        1
I2C_DRIVE_FLT_LED_SCL6                 1
I2C_DRIVE_FLT_LED_SCL6_LS              1
I2C_DRIVE_FLT_LED_SDA6                 1
I2C_DRIVE_FLT_LED_SDA6_LS              1
I2C_DRIVE_INS_SCL5                     1
I2C_DRIVE_INS_SCL5_LS                  1
I2C_DRIVE_INS_SDA5                     1
I2C_DRIVE_INS_SDA5_LS                  1
I2C_DRIVE_PWR_SCL4                     1
I2C_DRIVE_PWR_SCL4_LS                  1
I2C_DRIVE_PWR_SDA4                     1
I2C_DRIVE_PWR_SDA4_LS                  1
I2C_EXP_IOC_SCL8                       1
I2C_EXP_IOC_SDA8                       1
I2C_IOC_0_SCL                          1
I2C_IOC_0_SDA                          1
I2C_IOC_1_SCL                          1
I2C_IOC_1_SDA                          1
I2C_IOC_2_SCL                          1
I2C_IOC_2_SDA                          1
I2C_IOC_3_SCL                          1
I2C_IOC_3_SDA                          1
I2C_IOC_4_R_SCL                        1
I2C_IOC_4_R_SDA                        1
I2C_IOC_4_SCL                          1
I2C_IOC_4_SDA                          1
I2C_SCC_SCL2                           1
I2C_SCC_SCL2_LS                        1
I2C_SCC_SDA2                           1
I2C_SCC_SDA2_LS                        1
ICE0_TCK                               1
ICE0_TDI                               1
ICE0_TDO                               1
ICE0_TMS                               1
ICE0_TRST#                             1
ICE1_TCK                               1
ICE1_TDI                               1
ICE1_TDO                               1
ICE1_TMS                               1
ICE1_TRST#                             1
ICE_RESET_N                            1
ICE_SEL                                1
ICE_TCK                                1
ICE_TDI                                1
ICE_TDO                                1
ICE_TMS                                1
ICE_TRST_N                             1
INT_A1_CONN1                           1
INT_A2_CONN1                           1
INT_B1_CONN1                           1
INT_B2_CONN1                           1
INT_C1_CONN1                           1
INT_C2_CONN1                           1
INT_D1_CONN1                           1
INT_D2_CONN1                           1
IOC_CLK_SEL0                           1
IOC_CLK_SEL1                           1
IOC_EEPROM_A0                          1
IOC_EEPROM_A1                          1
IOC_EEPROM_A2                          1
IOC_EEPROM_SCL                         1
IOC_EEPROM_SDA                         1
IOC_EEPROM_WP                          1
IOC_GPIO_0                             1
IOC_GPIO_1                             1
IOC_GPIO_10                            1
IOC_GPIO_11                            1
IOC_GPIO_12                            1
IOC_GPIO_13                            1
IOC_GPIO_14                            1
IOC_GPIO_15                            1
IOC_GPIO_16                            1
IOC_GPIO_17                            1
IOC_GPIO_18                            1
IOC_GPIO_19                            1
IOC_GPIO_2                             1
IOC_GPIO_20                            1
IOC_GPIO_21                            1
IOC_GPIO_22                            1
IOC_GPIO_23                            1
IOC_GPIO_24                            1
IOC_GPIO_25                            1
IOC_GPIO_26                            1
IOC_GPIO_27                            1
IOC_GPIO_28                            1
IOC_GPIO_29                            1
IOC_GPIO_3                             1
IOC_GPIO_30                            1
IOC_GPIO_31                            1
IOC_GPIO_32                            1
IOC_GPIO_33                            1
IOC_GPIO_34                            1
IOC_GPIO_35                            1
IOC_GPIO_36                            1
IOC_GPIO_37                            1
IOC_GPIO_38                            1
IOC_GPIO_39                            1
IOC_GPIO_4                             1
IOC_GPIO_5                             1
IOC_GPIO_6                             1
IOC_GPIO_7                             1
IOC_GPIO_8                             1
IOC_GPIO_9                             1
IOC_RESET_N                            1
IOC_SIO_BLINK                          1
IOC_TDO                                1
IOC_TRST_N                             1
IOC_UART_0_RX                          1
IOC_UART_0_RX_R                        1
IOC_UART_0_TX                          1
IOC_UART_0_TX_R                        1
IOC_UART_1_RX                          1
IOC_UART_1_TX                          1
IOC_UART_R_RX                          1
IOC_UART_R_TX                          1
IOC_VREF_SET                           1
IOC_VREF_SET_LS                        1
IOC_WP_N                               1
JTAG_EXP_TCK                           1
JTAG_EXP_TDI                           1
JTAG_EXP_TDO                           1
JTAG_EXP_TMS                           1
JTAG_IOC_TCK                           1
JTAG_IOC_TDI                           1
JTAG_IOC_TMS                           1
LED11                                  1
LED40                                  1
LED41                                  1
LED42                                  1
LED43                                  1
LED44                                  1
LED45                                  1
LED46                                  1
LED47                                  1
LED8                                   1
LSI_EFUSE                              1
LSI_IDDT                               1
LSI_JTAG_EN_N                          1
LSI_PROCMON                            1
LSI_SCAN_EN                            1
LSI_SCAN_ENABLE                        1
LSI_TN                                 1
LSI_TRST_N                             1
LSI_T_N                                1
LS_EN_N                                1
LS_EN_U12                              1
LS_EN_U14                              1
LS_EN_U24                              1
LS_EN_U35                              1
LS_EN_U36                              1
LS_EN_U37                              1
LS_EN_U38                              1
LS_EN_U39                              1
LS_EN_U40                              1
LS_EN_U41                              1
LS_EN_U46                              1
MB0_12V_CTRL_GATE1                     1
MB0_12V_CTRL_GATE1_R                   1
MB0_CM_ADR1_R                          1
MB0_CM_ADR2_R                          1
MB0_CM_GATE                            1
MB0_CM_GATE_R                          1
MB0_CM_OV_R                            1
MB0_CM_SENSE_N                         1
MB0_CM_SENSE_P                         1
MB0_CM_SENSE_R1_N                      1
MB0_CM_SENSE_R1_P                      1
MB0_CM_UV_R                            1
MB0_CM_VOUT_R                          1
MB0_HS_ENABLE                          1
MB0_HS_ENABLE_R                        1
MB0_ISET_R                             1
MB0_ISTART_R                           1
MB0_P12V_MAIN_R                        1
MB0_P12V_PWGIN_R                       1
MB0_PSET_R                             1
MB0_RETRY_R                            1
MB0_SPISS_PD                           1
MB0_TEMP                               1
MB0_TEMP_C                             1
MB0_TEMP_E                             1
MB0_TIME_R                             1
MB0_VCAP_R                             1
MB0_VCC                                1
OSC_REF_CLK                            1
P0V975                                 1
P0V975_SEN                             1
P0V975_SENSE                           1
P0V975_STAT                            1
P0V9_BST                               1
P0V9_BST_R                             1
P0V9_COMP                              1
P0V9_DH                                1
P0V9_DL                                1
P0V9_EN                                1
P0V9_GSNS                              1
P0V9_G_PG                              1
P0V9_MODE                              1
P0V9_PG                                1
P0V9_PG_Q                              1
P0V9_REFIN                             1
P0V9_SENSE                             1
P0V9_SW                                1
P0V9_TG                                1
P0V9_TRIP                              1
P0V9_U8_PG                             1
P0V9_V5                                1
P0V9_VFB                               1
P0V9_VREF                              1
P0V9_VSNS                              1
P12V_SCC_PGOOD                         1
P12V_STBY_Q10_G                        1
P12V_STBY_Q12_G                        1
P12V_STBY_SCC                          1
P12V_STBY_VDD_U10                      1
P12V_STBY_VDD_U11                      1
P12V_STBY_VIN_U11                      1
P12V_SYBY_VDD_U6                       1
P1V5_C                                 1
P1V5_C_G                               1
P1V5_C_PG                              1
P1V5_C_PG_G                            1
P1V5_C_PG_R_1                          1
P1V5_C_S                               1
P1V5_C_SENSE                           1
P1V5_E_EN                              1
P1V5_E_LL                              1
P1V5_E_LL_R                            1
P1V5_E_MODE                            1
P1V5_E_PG                              1
P1V5_E_RC                              1
P1V5_E_RF                              1
P1V5_E_SENSE                           1
P1V5_E_SNB                             1
P1V5_E_TRIP                            1
P1V5_E_VBST                            1
P1V5_E_VFB                             1
P1V5_E_VFB_R                           1
P1V8_C_G                               1
P1V8_C_G_PG                            1
P1V8_C_PG                              1
P1V8_C_PG_G                            1
P1V8_C_PG_LS                           1
P1V8_C_PG_R_1                          1
P1V8_C_S                               1
P1V8_C_SENSE                           1
P1V8_E_BIAS                            1
P1V8_E_EN                              1
P1V8_E_FB                              1
P1V8_E_OUT                             1
P1V8_E_PG                              1
P1V8_E_SENSE                           1
P1V8_E_SS                              1
P3V3_DPB                               1
P3V3_EN                                1
P3V3_LL_R                              1
P3V3_MODE                              1
P3V3_OUT                               1
P3V3_RF                                1
P3V3_SENSE                             1
P3V3_SNB                               1
P3V3_STBY_Q15_R                        1
P3V3_STBY_R                            1
P3V3_TRIP                              1
P3V3_VBST                              1
P3V3_VFB                               1
P3V3_VFB_R                             1
P3V3_VREG                              1
PCE_AVDD                               1
PCE_VDDH                               1
PCIE_COMP_TO_SCC_RST_0                 1
PCIE_COMP_TO_SCC_RST_R_0               1
PCIE_RST_N                             1
PG_CORE                                1
PHY_CLK                                1
PLLDDR_VDDA18                          1
PLL_VDD                                1
POWERLOSS#                             1
PWM_OUT_ZONE_C                         1
PWM_OUT_ZONE_C_LS                      1
PWM_OUT_ZONE_D                         1
PWM_OUT_ZONE_D_LS                      1
Q22_D                                  1
RESET_CT                               1
RESET_MR#                              1
RESET_SENSE                            1
RTRIM                                  1
RTRIM#                                 1
RTRIM_A                                1
RTRIM_AN                               1
SAS0_VDDH                              1
SAS_R_SDBTX                            1
SAS_SMART_RX                           1
SAS_SMART_R_RX                         1
SAS_SMART_R_TX                         1
SAS_SMART_TX                           1
SBL_SCL                                1
SBL_SDA                                1
SCC_FULL_PGOOD                         1
SCC_FULL_PGOOD_BUF                     1
SCC_FULL_PGOOD_BUF_R                   1
SCC_FULL_PGOOD_LS                      1
SCC_FULL_PGOOD_SENSE                   1
SCC_FULL_PWR_BUF_EN                    1
SCC_FULL_PWR_BUF_EN_U48                1
SCC_FULL_PWR_EN                        1
SCC_FULL_PWR_EN_U48                    1
SCC_FULL_PWR_EN_U49                    1
SCC_HSC_N                              1
SCC_LOC_HEARTBEAT                      1
SCC_LOC_HEARTBEAT_LS                   1
SCC_LOC_INS_N                          1
SCC_RESET_BUF_N                        1
SCC_RESET_LS_N                         1
SCC_RESET_LS_R_N                       1
SCC_RESET_N                            1
SCC_RMT_HEARTBEAT                      1
SCC_RMT_HEARTBEAT_LS                   1
SCC_STBY_PGOOD                         1
SCC_STBY_PGOOD_BUF                     1
SCC_STBY_PGOOD_R                       1
SCC_STBY_PGOOD_U49                     1
SCC_STBY_PWR_BUF_EN                    1
SCC_STBY_PWR_EN                        1
SCC_TYPE_0                             1
SCC_TYPE_0_LS                          1
SCC_TYPE_1                             1
SCC_TYPE_1_LS                          1
SCC_TYPE_2                             1
SCC_TYPE_2_LS                          1
SCC_TYPE_3                             1
SCC_TYPE_3_LS                          1
SDB_CONN_PWR_2                         1
SDB_CONN_PWR_3                         1
SDB_RX                                 1
SDB_RX_R                               1
SDB_R_RX                               1
SDB_R_TX                               1
SDB_TX                                 1
SDB_TX_R                               1
SDB_UART_EN                            1
SHELL_PLL_VDD                          1
SIO_CLK_0                              1
SIO_CLK_1                              1
SIO_DIN_0                              1
SIO_DIN_1                              1
SIO_DOUT_0                             1
SIO_DOUT_1                             1
SIO_LOAD_0                             1
SIO_LOAD_1                             1
SLOT_ID_0                              1
SLOT_ID_1                              1
SMART_RX                               1
SMART_TX                               1
SMART_UART_EN                          1
SOFT_RESET_N                           1
SPARE0                                 1
SPARE1                                 1
SPARE2                                 1
SPARE3                                 1
SPARE4                                 1
SPARE5                                 1
SXP_ACTIVE_0                           1
SXP_ACTIVE_1                           1
SXP_ACTIVE_2                           1
SYSPLL_VDDA09                          1
SYSPLL_VDDA18                          1
SYS_CORE_TRI#                          1
SYS_DBMODE0                            1
SYS_DBMODE1                            1
SYS_DBMODE2                            1
SYS_DBMODE3                            1
SYS_DBMODE4                            1
SYS_ERROR1                             1
SYS_ERR_0                              1
SYS_HALT0#                             1
SYS_HALT1#                             1
SYS_HB_LED                             1
SYS_HB_LED_D                           1
SYS_PLL_VDD                            1
SYS_PWR_LED_LS_N                       1
SYS_PWR_LED_N                          1
SYS_RST                                1
SYS_RST_N_1                            1
SYS_RST_Q8                             1
TEMP2_A0                               1
TEMP2_A1                               1
TEMP2_A2                               1
TEMP2_ALERT                            1
TEMP2_SCL                              1
TEMP2_SDA                              1
TESTIBIAS                              1
TMUX_EN                                1
U118_VCC                               1
U119_EN                                1
U120_EN                                1
U122_VCC                               1
U47_OE                                 1
U48_OE                                 1
U49_OE                                 1
U50_OE                                 1
UART_CTS                               1
UART_EXP_RX                            1
UART_EXP_TX                            1
UART_IOC_RX                            1
UART_IOC_TX                            1
UART_RTS                               1
UART_SDB_RX                            1
UART_SDB_TX                            1
UART_SERCLK                            1
USB_CLK                                1
USB_DIR                                1
USB_NXT                                1
VDDA_SAS_REF_CLK                       1
VDDIO_15                               1
VOL_SEN1_ADDR                          1
VOL_SEN1_ALERT                         1
VOL_SEN1_SCL                           1
VOL_SEN1_SDA                           1
VOL_SEN2_ADDR                          1
VOL_SEN2_ALERT                         1
VOL_SEN2_SCL                           1
VOL_SEN2_SDA                           1
VREF0                                  1
VREF1                                  1
VREF2                                  1
VREF3                                  1
VREF4                                  1
VREF5                                  1
VREF6                                  1
VREF7                                  1
VT235_AVDD                             1
VT235_BIAS                             1
VT235_BST                              1
VT235_EN                               1
VT235_IMAX                             1
VT235_IRIP                             1
VT235_PGIN                             1
VT235_VDDL                             1
VT235_VDES                             1
VT235_VDES_RC                          1
VT235_VDES_RCC                         1
VT235_VDES_RR                          1
VT235_VFB                              1
VT235_VREF                             1
VT235_VX                               1
XTAL_VDDA09                            1
XTAL_VDDA18                            1

MB0_HS_SENSE_N                         0
MB0_HS_SENSE_P                         0
P0V9_BG                                0
P0V9_SNB                               0
P0V9_VSW                               0
P1V5_E_ROVP                            0
P1V5_E_VREG                            0
P3V3_ROVP                              0
P3V3_VBST_RC                           0
SAS_R_SDBRX                            0
SYS_ERROR_LED_D                        0
SYS_ERROR_LED_R                        0
SYS_HB_LED_R                           0
VDDIO_DDR                              0
VT235_VX_R                             0
